FILE_TYPE=LIBRARY_PARTS;
primitive 'SCONN24_H46321001','SCONN24_H46321001_SM';
  pin
    'IO1':
      PIN_NUMBER='(1)';
      BIDIRECTIONAL='TRUE';
      INPUT_LOAD='(-0.01,0.01)';
      OUTPUT_LOAD='(1.0,-1.0)';
    'IO10':
      PIN_NUMBER='(10)';
      BIDIRECTIONAL='TRUE';
      INPUT_LOAD='(-0.01,0.01)';
      OUTPUT_LOAD='(1.0,-1.0)';
    'IO11':
      PIN_NUMBER='(11)';
      BIDIRECTIONAL='TRUE';
      INPUT_LOAD='(-0.01,0.01)';
      OUTPUT_LOAD='(1.0,-1.0)';
    'IO12':
      PIN_NUMBER='(12)';
      BIDIRECTIONAL='TRUE';
      INPUT_LOAD='(-0.01,0.01)';
      OUTPUT_LOAD='(1.0,-1.0)';
    'IO13':
      PIN_NUMBER='(13)';
      BIDIRECTIONAL='TRUE';
      INPUT_LOAD='(-0.01,0.01)';
      OUTPUT_LOAD='(1.0,-1.0)';
    'IO14':
      PIN_NUMBER='(14)';
      BIDIRECTIONAL='TRUE';
      INPUT_LOAD='(-0.01,0.01)';
      OUTPUT_LOAD='(1.0,-1.0)';
    'IO15':
      PIN_NUMBER='(15)';
      BIDIRECTIONAL='TRUE';
      INPUT_LOAD='(-0.01,0.01)';
      OUTPUT_LOAD='(1.0,-1.0)';
    'IO16':
      PIN_NUMBER='(16)';
      BIDIRECTIONAL='TRUE';
      INPUT_LOAD='(-0.01,0.01)';
      OUTPUT_LOAD='(1.0,-1.0)';
    'IO17':
      PIN_NUMBER='(17)';
      BIDIRECTIONAL='TRUE';
      INPUT_LOAD='(-0.01,0.01)';
      OUTPUT_LOAD='(1.0,-1.0)';
    'IO18':
      PIN_NUMBER='(18)';
      BIDIRECTIONAL='TRUE';
      INPUT_LOAD='(-0.01,0.01)';
      OUTPUT_LOAD='(1.0,-1.0)';
    'IO19':
      PIN_NUMBER='(19)';
      BIDIRECTIONAL='TRUE';
      INPUT_LOAD='(-0.01,0.01)';
      OUTPUT_LOAD='(1.0,-1.0)';
    'IO2':
      PIN_NUMBER='(2)';
      BIDIRECTIONAL='TRUE';
      INPUT_LOAD='(-0.01,0.01)';
      OUTPUT_LOAD='(1.0,-1.0)';
    'IO20':
      PIN_NUMBER='(20)';
      BIDIRECTIONAL='TRUE';
      INPUT_LOAD='(-0.01,0.01)';
      OUTPUT_LOAD='(1.0,-1.0)';
    'IO21':
      PIN_NUMBER='(21)';
      BIDIRECTIONAL='TRUE';
      INPUT_LOAD='(-0.01,0.01)';
      OUTPUT_LOAD='(1.0,-1.0)';
    'IO22':
      PIN_NUMBER='(22)';
      BIDIRECTIONAL='TRUE';
      INPUT_LOAD='(-0.01,0.01)';
      OUTPUT_LOAD='(1.0,-1.0)';
    'IO23':
      PIN_NUMBER='(23)';
      BIDIRECTIONAL='TRUE';
      INPUT_LOAD='(-0.01,0.01)';
      OUTPUT_LOAD='(1.0,-1.0)';
    'IO24':
      PIN_NUMBER='(24)';
      BIDIRECTIONAL='TRUE';
      INPUT_LOAD='(-0.01,0.01)';
      OUTPUT_LOAD='(1.0,-1.0)';
    'IO3':
      PIN_NUMBER='(3)';
      BIDIRECTIONAL='TRUE';
      INPUT_LOAD='(-0.01,0.01)';
      OUTPUT_LOAD='(1.0,-1.0)';
    'IO4':
      PIN_NUMBER='(4)';
      BIDIRECTIONAL='TRUE';
      INPUT_LOAD='(-0.01,0.01)';
      OUTPUT_LOAD='(1.0,-1.0)';
    'IO5':
      PIN_NUMBER='(5)';
      BIDIRECTIONAL='TRUE';
      INPUT_LOAD='(-0.01,0.01)';
      OUTPUT_LOAD='(1.0,-1.0)';
    'IO6':
      PIN_NUMBER='(6)';
      BIDIRECTIONAL='TRUE';
      INPUT_LOAD='(-0.01,0.01)';
      OUTPUT_LOAD='(1.0,-1.0)';
    'IO7':
      PIN_NUMBER='(7)';
      BIDIRECTIONAL='TRUE';
      INPUT_LOAD='(-0.01,0.01)';
      OUTPUT_LOAD='(1.0,-1.0)';
    'IO8':
      PIN_NUMBER='(8)';
      BIDIRECTIONAL='TRUE';
      INPUT_LOAD='(-0.01,0.01)';
      OUTPUT_LOAD='(1.0,-1.0)';
    'IO9':
      PIN_NUMBER='(9)';
      BIDIRECTIONAL='TRUE';
      INPUT_LOAD='(-0.01,0.01)';
      OUTPUT_LOAD='(1.0,-1.0)';
    'MP1':
      PIN_NUMBER='(MP1)';
      PINUSE='GROUND';
      NO_LOAD_CHECK='Both';
      NO_IO_CHECK='Both';
      NO_ASSERT_CHECK='TRUE';
      NO_DIR_CHECK='TRUE';
      ALLOW_CONNECT='TRUE';
    'MP2':
      PIN_NUMBER='(MP2)';
      PINUSE='GROUND';
      NO_LOAD_CHECK='Both';
      NO_IO_CHECK='Both';
      NO_ASSERT_CHECK='TRUE';
      NO_DIR_CHECK='TRUE';
      ALLOW_CONNECT='TRUE';
  end_pin;
  body
    PART_NAME='SCONN24_H46321001';
    PHYS_DES_PREFIX='J';
  end_body;
end_primitive;

END.
